(kicad_pcb
	(version 20260206)
	(generator "pcbnew")
	(generator_version "10.0")
	(general
		(thickness 1.6)
		(legacy_teardrops no)
	)
	(paper "A4")
	(title_block
		(title "peb — Lightning_PEB_BRD.brd")
		(comment 1 "Lightning (Wiwynn / Facebook NVMe JBOF) / footprints 73-80 of 2563")
	)
	(layers
		(0 "F.Cu" signal "TOP")
		(4 "In1.Cu" signal "L2GND")
		(6 "In2.Cu" signal "L3")
		(8 "In3.Cu" signal "L4VCC")
		(10 "In4.Cu" signal "L5VCC")
		(12 "In5.Cu" signal "L6")
		(14 "In6.Cu" signal "L7GND")
		(2 "B.Cu" signal "BOTTOM")
		(9 "F.Adhes" user "F.Adhesive")
		(11 "B.Adhes" user "B.Adhesive")
		(13 "F.Paste" user "Package Geometry/Pastemask Top")
		(15 "B.Paste" user "Package Geometry/Pastemask Bottom")
		(5 "F.SilkS" user "Ref Des/Silkscreen Top")
		(7 "B.SilkS" user "Ref Des/Silkscreen Bottom")
		(1 "F.Mask" user "Board Geometry/Soldermask Top")
		(3 "B.Mask" user "Board Geometry/Soldermask Bottom")
		(17 "Dwgs.User" user "User.Drawings")
		(19 "Cmts.User" user "User.Comments")
		(21 "Eco1.User" user "User.Eco1")
		(23 "Eco2.User" user "User.Eco2")
		(25 "Edge.Cuts" user "Board Geometry/Outline")
		(27 "Margin" user)
		(31 "F.CrtYd" user "Package Geometry/Place Bound Top")
		(29 "B.CrtYd" user "Package Geometry/Place Bound Bottom")
		(35 "F.Fab" user "Ref Des/Assembly Top")
		(33 "B.Fab" user "Ref Des/Assembly Bottom")
	)
	(footprint ""
		(layer "F.Cu")
		(at 53.721 -119.126 -90)
		(property "Reference" "R461"
			(at 0 0 270)
			(layer "F.SilkS")
			(hide yes)
			(effects
				(font
					(size 1.27 1.27)
				)
			)
		)
		(property "Value" "0R2J-2-GP"
			(at 0.064008 -3.993896 270)
			(unlocked yes)
			(layer "F.Fab")
			(hide yes)
			(effects
				(font
					(size 1.016 1.016)
					(thickness 0.1524)
				)
			)
		)
		(property "Device Type" "R402H16"
			(at 0.064008 -5.517896 270)
			(unlocked yes)
			(layer "F.Fab")
			(hide yes)
			(effects
				(font
					(size 1.016 1.016)
					(thickness 0.1524)
				)
			)
		)
		(duplicate_pad_numbers_are_jumpers no)
		(fp_line
			(start -0.508 -0.9398)
			(end -0.508 0.9398)
			(stroke
				(width 0.1524)
				(type default)
			)
			(layer "F.SilkS")
		)
		(fp_line
			(start 0.508 -0.9398)
			(end -0.508 -0.9398)
			(stroke
				(width 0.1524)
				(type default)
			)
			(layer "F.SilkS")
		)
		(fp_rect
			(start -0.508 0.9398)
			(end 0.508 -0.9398)
			(stroke
				(width 0)
				(type default)
			)
			(fill no)
			(layer "F.CrtYd")
		)
		(fp_rect
			(start -0.508 0.9398)
			(end 0.508 -0.9398)
			(stroke
				(width 0)
				(type default)
			)
			(fill no)
			(layer "F.Fab")
		)
		(pad "1" smd custom
			(at 0 -0.4445 270)
			(size 0.1397 0.1397)
			(layers "F.Cu" "F.Mask" "F.Paste")
			(net "BMC_I2C7_B_DBP_SCL")
			(options
				(clearance outline)
				(anchor circle)
			)
			(primitives
				(gr_poly
					(pts
						(arc
							(start -0.1778 -0.2794)
							(mid -0.249642 -0.249642)
							(end -0.2794 -0.1778)
						)
						(arc
							(start -0.2794 0.1778)
							(mid -0.249642 0.249642)
							(end -0.1778 0.2794)
						)
						(arc
							(start 0.1778 0.2794)
							(mid 0.249642 0.249642)
							(end 0.2794 0.1778)
						)
						(arc
							(start 0.2794 -0.1778)
							(mid 0.249642 -0.249642)
							(end 0.1778 -0.2794)
						)
					)
					(width 0)
					(fill yes)
				)
			)
		)
		(pad "2" smd custom
			(at 0 0.4445 270)
			(size 0.1397 0.1397)
			(layers "F.Cu" "F.Mask" "F.Paste")
			(net "BMC0_SMB7_CLK")
			(options
				(clearance outline)
				(anchor circle)
			)
			(primitives
				(gr_poly
					(pts
						(arc
							(start -0.1778 -0.2794)
							(mid -0.249642 -0.249642)
							(end -0.2794 -0.1778)
						)
						(arc
							(start -0.2794 0.1778)
							(mid -0.249642 0.249642)
							(end -0.1778 0.2794)
						)
						(arc
							(start 0.1778 0.2794)
							(mid 0.249642 0.249642)
							(end 0.2794 0.1778)
						)
						(arc
							(start 0.2794 -0.1778)
							(mid 0.249642 -0.249642)
							(end 0.1778 -0.2794)
						)
					)
					(width 0)
					(fill yes)
				)
			)
		)
	)
	(footprint ""
		(layer "F.Cu")
		(at 33.857946 -146.48688 180)
		(property "Reference" "C184"
			(at 0 0 180)
			(layer "F.SilkS")
			(hide yes)
			(effects
				(font
					(size 1.27 1.27)
				)
			)
		)
		(property "Value" "SCD1U16V2KX-3GP"
			(at 1.1811 -2.7051 180)
			(unlocked yes)
			(layer "F.Fab")
			(hide yes)
			(effects
				(font
					(size 1.016 1.016)
					(thickness 0.1524)
				)
			)
		)
		(property "Device Type" "C402H22"
			(at 1.1811 -4.2291 180)
			(unlocked yes)
			(layer "F.Fab")
			(hide yes)
			(effects
				(font
					(size 1.016 1.016)
					(thickness 0.1524)
				)
			)
		)
		(duplicate_pad_numbers_are_jumpers no)
		(fp_rect
			(start -0.4318 0.9525)
			(end 0.4318 -0.9525)
			(stroke
				(width 0)
				(type default)
			)
			(fill no)
			(layer "F.CrtYd")
		)
		(fp_rect
			(start -0.4318 0.9525)
			(end 0.4318 -0.9525)
			(stroke
				(width 0)
				(type default)
			)
			(fill no)
			(layer "F.Fab")
		)
		(pad "1" smd custom
			(at 0 -0.4445 180)
			(size 0.1524 0.1524)
			(layers "F.Cu" "F.Mask" "F.Paste")
			(net "GND")
			(options
				(clearance outline)
				(anchor circle)
			)
			(primitives
				(gr_poly
					(pts
						(arc
							(start 0.3048 -0.2032)
							(mid 0.275042 -0.275042)
							(end 0.2032 -0.3048)
						)
						(arc
							(start -0.2032 -0.3048)
							(mid -0.275042 -0.275042)
							(end -0.3048 -0.2032)
						)
						(arc
							(start -0.3048 0.2032)
							(mid -0.275042 0.275042)
							(end -0.2032 0.3048)
						)
						(arc
							(start 0.2032 0.3048)
							(mid 0.275042 0.275042)
							(end 0.3048 0.2032)
						)
					)
					(width 0)
					(fill yes)
				)
			)
		)
		(pad "2" smd custom
			(at 0 0.4445 180)
			(size 0.1524 0.1524)
			(layers "F.Cu" "F.Mask" "F.Paste")
			(net "DDR_VREF")
			(options
				(clearance outline)
				(anchor circle)
			)
			(primitives
				(gr_poly
					(pts
						(arc
							(start 0.3048 -0.2032)
							(mid 0.275042 -0.275042)
							(end 0.2032 -0.3048)
						)
						(arc
							(start -0.2032 -0.3048)
							(mid -0.275042 -0.275042)
							(end -0.3048 -0.2032)
						)
						(arc
							(start -0.3048 0.2032)
							(mid -0.275042 0.275042)
							(end -0.2032 0.3048)
						)
						(arc
							(start 0.2032 0.3048)
							(mid 0.275042 0.275042)
							(end 0.3048 0.2032)
						)
					)
					(width 0)
					(fill yes)
				)
			)
		)
	)
	(footprint ""
		(layer "F.Cu")
		(at 31.369 -70.4596 -90)
		(property "Reference" "PC72"
			(at 0 0 270)
			(layer "F.SilkS")
			(hide yes)
			(effects
				(font
					(size 1.27 1.27)
				)
			)
		)
		(property "Value" "SC4D7U25V5KX-1-GP"
			(at -0.0762 -6.1214 270)
			(unlocked yes)
			(layer "F.Fab")
			(hide yes)
			(effects
				(font
					(size 1.016 1.016)
					(thickness 0.1524)
				)
			)
		)
		(property "Device Type" "C805H58"
			(at -0.0762 -8.1534 270)
			(unlocked yes)
			(layer "F.Fab")
			(hide yes)
			(effects
				(font
					(size 1.016 1.016)
					(thickness 0.1524)
				)
			)
		)
		(duplicate_pad_numbers_are_jumpers no)
		(fp_line
			(start 0.635 0)
			(end -0.635 0)
			(stroke
				(width 0.508)
				(type default)
			)
			(layer "F.SilkS")
		)
		(fp_rect
			(start -0.9652 1.778)
			(end 0.9652 -1.778)
			(stroke
				(width 0)
				(type default)
			)
			(fill no)
			(layer "F.CrtYd")
		)
		(fp_poly
			(pts
				(xy -0.9652 -1.778) (xy 0.9652 -1.778) (xy 0.9652 1.778) (xy -0.9652 1.778)
			)
			(stroke
				(width 0)
				(type default)
			)
			(fill no)
			(layer "F.Fab")
		)
		(pad "1" smd rect
			(at 0 -0.9652 270)
			(size 1.397 1.143)
			(layers "F.Cu" "F.Mask" "F.Paste")
			(net "P12V")
		)
		(pad "2" smd rect
			(at 0 0.9652 270)
			(size 1.397 1.143)
			(layers "F.Cu" "F.Mask" "F.Paste")
			(net "GND")
		)
	)
	(footprint ""
		(layer "F.Cu")
		(at 24.0538 -85.2424 -90)
		(property "Reference" "TP170"
			(at 0 0 270)
			(layer "F.SilkS")
			(hide yes)
			(effects
				(font
					(size 1.27 1.27)
				)
			)
		)
		(property "Value" "TPAD28-2-GP"
			(at -0.0127 -1.6637 270)
			(unlocked yes)
			(layer "F.Fab")
			(hide yes)
			(effects
				(font
					(size 1.016 1.016)
					(thickness 0.1524)
				)
			)
		)
		(property "Device Type" "TPAD28"
			(at -0.0127 -3.1877 270)
			(unlocked yes)
			(layer "F.Fab")
			(hide yes)
			(effects
				(font
					(size 1.016 1.016)
					(thickness 0.1524)
				)
			)
		)
		(duplicate_pad_numbers_are_jumpers no)
		(fp_poly
			(pts
				(arc
					(start 0 -0.3556)
					(mid 0 0.3556)
					(end 0 -0.3556)
				)
			)
			(stroke
				(width 0)
				(type default)
			)
			(fill no)
			(layer "F.CrtYd")
		)
		(fp_poly
			(pts
				(arc
					(start 0 -0.6096)
					(mid 0 0.6096)
					(end 0 -0.6096)
				)
			)
			(stroke
				(width 0)
				(type default)
			)
			(fill no)
			(layer "F.Fab")
		)
		(pad "1" smd circle
			(at 0 0 270)
			(size 0.7112 0.7112)
			(layers "F.Cu" "F.Mask" "F.Paste")
			(net "NIC_JTMS")
		)
	)
	(footprint ""
		(layer "F.Cu")
		(at 266.9794 -16.2814 -90)
		(property "Reference" "SR717"
			(at 0 0 270)
			(layer "F.SilkS")
			(hide yes)
			(effects
				(font
					(size 1.27 1.27)
				)
			)
		)
		(property "Value" "150R2F-1-GP"
			(at 0.064008 -3.993896 270)
			(unlocked yes)
			(layer "F.Fab")
			(hide yes)
			(effects
				(font
					(size 1.016 1.016)
					(thickness 0.1524)
				)
			)
		)
		(property "Device Type" "R402H16"
			(at 0.064008 -5.517896 270)
			(unlocked yes)
			(layer "F.Fab")
			(hide yes)
			(effects
				(font
					(size 1.016 1.016)
					(thickness 0.1524)
				)
			)
		)
		(duplicate_pad_numbers_are_jumpers no)
		(fp_line
			(start -0.508 -0.9398)
			(end -0.508 0.9398)
			(stroke
				(width 0.1524)
				(type default)
			)
			(layer "F.SilkS")
		)
		(fp_line
			(start 0.508 -0.9398)
			(end -0.508 -0.9398)
			(stroke
				(width 0.1524)
				(type default)
			)
			(layer "F.SilkS")
		)
		(fp_rect
			(start -0.508 0.9398)
			(end 0.508 -0.9398)
			(stroke
				(width 0)
				(type default)
			)
			(fill no)
			(layer "F.CrtYd")
		)
		(fp_rect
			(start -0.508 0.9398)
			(end 0.508 -0.9398)
			(stroke
				(width 0)
				(type default)
			)
			(fill no)
			(layer "F.Fab")
		)
		(pad "1" smd custom
			(at 0 -0.4445 270)
			(size 0.1397 0.1397)
			(layers "F.Cu" "F.Mask" "F.Paste")
			(net "P3V3_STBY")
			(options
				(clearance outline)
				(anchor circle)
			)
			(primitives
				(gr_poly
					(pts
						(arc
							(start -0.1778 -0.2794)
							(mid -0.249642 -0.249642)
							(end -0.2794 -0.1778)
						)
						(arc
							(start -0.2794 0.1778)
							(mid -0.249642 0.249642)
							(end -0.1778 0.2794)
						)
						(arc
							(start 0.1778 0.2794)
							(mid 0.249642 0.249642)
							(end 0.2794 0.1778)
						)
						(arc
							(start 0.2794 -0.1778)
							(mid 0.249642 -0.249642)
							(end 0.1778 -0.2794)
						)
					)
					(width 0)
					(fill yes)
				)
			)
		)
		(pad "2" smd custom
			(at 0 0.4445 270)
			(size 0.1397 0.1397)
			(layers "F.Cu" "F.Mask" "F.Paste")
			(net "LED_R_12")
			(options
				(clearance outline)
				(anchor circle)
			)
			(primitives
				(gr_poly
					(pts
						(arc
							(start -0.1778 -0.2794)
							(mid -0.249642 -0.249642)
							(end -0.2794 -0.1778)
						)
						(arc
							(start -0.2794 0.1778)
							(mid -0.249642 0.249642)
							(end -0.1778 0.2794)
						)
						(arc
							(start 0.1778 0.2794)
							(mid 0.249642 0.249642)
							(end 0.2794 0.1778)
						)
						(arc
							(start 0.2794 -0.1778)
							(mid 0.249642 -0.249642)
							(end 0.1778 -0.2794)
						)
					)
					(width 0)
					(fill yes)
				)
			)
		)
	)
	(footprint ""
		(layer "F.Cu")
		(at 192.9003 -19.2786 -90)
		(property "Reference" "R572"
			(at 0 0 270)
			(layer "F.SilkS")
			(hide yes)
			(effects
				(font
					(size 1.27 1.27)
				)
			)
		)
		(property "Value" "4K7R2F-GP"
			(at 0.064008 -3.993896 270)
			(unlocked yes)
			(layer "F.Fab")
			(hide yes)
			(effects
				(font
					(size 1.016 1.016)
					(thickness 0.1524)
				)
			)
		)
		(property "Device Type" "R402H16"
			(at 0.064008 -5.517896 270)
			(unlocked yes)
			(layer "F.Fab")
			(hide yes)
			(effects
				(font
					(size 1.016 1.016)
					(thickness 0.1524)
				)
			)
		)
		(duplicate_pad_numbers_are_jumpers no)
		(fp_line
			(start -0.508 -0.9398)
			(end -0.508 0.9398)
			(stroke
				(width 0.1524)
				(type default)
			)
			(layer "F.SilkS")
		)
		(fp_line
			(start 0.508 -0.9398)
			(end -0.508 -0.9398)
			(stroke
				(width 0.1524)
				(type default)
			)
			(layer "F.SilkS")
		)
		(fp_rect
			(start -0.508 0.9398)
			(end 0.508 -0.9398)
			(stroke
				(width 0)
				(type default)
			)
			(fill no)
			(layer "F.CrtYd")
		)
		(fp_rect
			(start -0.508 0.9398)
			(end 0.508 -0.9398)
			(stroke
				(width 0)
				(type default)
			)
			(fill no)
			(layer "F.Fab")
		)
		(pad "1" smd custom
			(at 0 -0.4445 270)
			(size 0.1397 0.1397)
			(layers "F.Cu" "F.Mask" "F.Paste")
			(net "MINISAS_CN15_C_I2C_INT#")
			(options
				(clearance outline)
				(anchor circle)
			)
			(primitives
				(gr_poly
					(pts
						(arc
							(start -0.1778 -0.2794)
							(mid -0.249642 -0.249642)
							(end -0.2794 -0.1778)
						)
						(arc
							(start -0.2794 0.1778)
							(mid -0.249642 0.249642)
							(end -0.1778 0.2794)
						)
						(arc
							(start 0.1778 0.2794)
							(mid 0.249642 0.249642)
							(end 0.2794 0.1778)
						)
						(arc
							(start 0.2794 -0.1778)
							(mid 0.249642 -0.249642)
							(end 0.1778 -0.2794)
						)
					)
					(width 0)
					(fill yes)
				)
			)
		)
		(pad "2" smd custom
			(at 0 0.4445 270)
			(size 0.1397 0.1397)
			(layers "F.Cu" "F.Mask" "F.Paste")
			(net "P3V3_STBY")
			(options
				(clearance outline)
				(anchor circle)
			)
			(primitives
				(gr_poly
					(pts
						(arc
							(start -0.1778 -0.2794)
							(mid -0.249642 -0.249642)
							(end -0.2794 -0.1778)
						)
						(arc
							(start -0.2794 0.1778)
							(mid -0.249642 0.249642)
							(end -0.1778 0.2794)
						)
						(arc
							(start 0.1778 0.2794)
							(mid 0.249642 0.249642)
							(end 0.2794 0.1778)
						)
						(arc
							(start 0.2794 -0.1778)
							(mid 0.249642 -0.249642)
							(end 0.1778 -0.2794)
						)
					)
					(width 0)
					(fill yes)
				)
			)
		)
	)
	(footprint ""
		(layer "F.Cu")
		(at 330.099924 -19.99996 -90)
		(property "Reference" "LED12"
			(at 0 0 270)
			(layer "F.SilkS")
			(hide yes)
			(effects
				(font
					(size 1.27 1.27)
				)
			)
		)
		(property "Value" "LED-YG-51-GP"
			(at -2.6924 -1.4224 270)
			(unlocked yes)
			(layer "F.Fab")
			(hide yes)
			(effects
				(font
					(size 1.016 1.016)
					(thickness 0.1524)
				)
			)
		)
		(property "Device Type" "LED1608AKH40"
			(at -2.6924 -2.9464 270)
			(unlocked yes)
			(layer "F.Fab")
			(hide yes)
			(effects
				(font
					(size 1.016 1.016)
					(thickness 0.1524)
				)
			)
		)
		(duplicate_pad_numbers_are_jumpers no)
		(fp_line
			(start -0.7493 1.651)
			(end -0.7493 1.1811)
			(stroke
				(width 0.3302)
				(type default)
			)
			(layer "F.SilkS")
		)
		(fp_line
			(start 0.7493 1.651)
			(end 0.7493 1.1811)
			(stroke
				(width 0.3302)
				(type default)
			)
			(layer "F.SilkS")
		)
		(fp_line
			(start -0.5969 1.5494)
			(end 0.5842 1.5494)
			(stroke
				(width 0.508)
				(type default)
			)
			(layer "F.SilkS")
		)
		(fp_line
			(start -0.6604 1.3716)
			(end -0.6604 -1.3716)
			(stroke
				(width 0.1524)
				(type default)
			)
			(layer "F.SilkS")
		)
		(fp_line
			(start 0.6604 1.3716)
			(end -0.6604 1.3716)
			(stroke
				(width 0.1524)
				(type default)
			)
			(layer "F.SilkS")
		)
		(fp_line
			(start -0.6604 -1.3716)
			(end 0.6604 -1.3716)
			(stroke
				(width 0.1524)
				(type default)
			)
			(layer "F.SilkS")
		)
		(fp_line
			(start 0.6604 -1.3716)
			(end 0.6604 1.3716)
			(stroke
				(width 0.1524)
				(type default)
			)
			(layer "F.SilkS")
		)
		(fp_rect
			(start -0.6223 1.3335)
			(end 0.6223 -1.3335)
			(stroke
				(width 0)
				(type default)
			)
			(fill no)
			(layer "F.CrtYd")
		)
		(fp_rect
			(start -0.6223 1.3335)
			(end 0.6223 -1.3335)
			(stroke
				(width 0)
				(type default)
			)
			(fill no)
			(layer "F.Fab")
		)
		(pad "A" smd custom
			(at 0 -0.762 270)
			(size 0.2159 0.2159)
			(layers "F.Cu" "F.Mask" "F.Paste")
			(net "LED_R_5")
			(options
				(clearance outline)
				(anchor circle)
			)
			(primitives
				(gr_poly
					(pts
						(arc
							(start -0.3302 -0.4318)
							(mid -0.402042 -0.402042)
							(end -0.4318 -0.3302)
						)
						(arc
							(start -0.4318 0.3302)
							(mid -0.402042 0.402042)
							(end -0.3302 0.4318)
						)
						(arc
							(start 0.3302 0.4318)
							(mid 0.402042 0.402042)
							(end 0.4318 0.3302)
						)
						(arc
							(start 0.4318 -0.3302)
							(mid 0.402042 -0.402042)
							(end 0.3302 -0.4318)
						)
					)
					(width 0)
					(fill yes)
				)
			)
		)
		(pad "K" smd custom
			(at 0 0.762 270)
			(size 0.2159 0.2159)
			(layers "F.Cu" "F.Mask" "F.Paste")
			(net "LED_Q_5")
			(options
				(clearance outline)
				(anchor circle)
			)
			(primitives
				(gr_poly
					(pts
						(arc
							(start -0.3302 -0.4318)
							(mid -0.402042 -0.402042)
							(end -0.4318 -0.3302)
						)
						(arc
							(start -0.4318 0.3302)
							(mid -0.402042 0.402042)
							(end -0.3302 0.4318)
						)
						(arc
							(start 0.3302 0.4318)
							(mid 0.402042 0.402042)
							(end 0.4318 0.3302)
						)
						(arc
							(start 0.4318 -0.3302)
							(mid 0.402042 -0.402042)
							(end 0.3302 -0.4318)
						)
					)
					(width 0)
					(fill yes)
				)
			)
		)
	)
	(footprint ""
		(layer "F.Cu")
		(at 221.9579 -203.0476 180)
		(property "Reference" "R7964"
			(at 0 0 180)
			(layer "F.SilkS")
			(hide yes)
			(effects
				(font
					(size 1.27 1.27)
				)
			)
		)
		(property "Value" "0R2J-2-GP"
			(at 0.064008 -3.993896 180)
			(unlocked yes)
			(layer "F.Fab")
			(hide yes)
			(effects
				(font
					(size 1.016 1.016)
					(thickness 0.1524)
				)
			)
		)
		(property "Device Type" "R402H16"
			(at 0.064008 -5.517896 180)
			(unlocked yes)
			(layer "F.Fab")
			(hide yes)
			(effects
				(font
					(size 1.016 1.016)
					(thickness 0.1524)
				)
			)
		)
		(duplicate_pad_numbers_are_jumpers no)
		(fp_line
			(start 0.508 -0.9398)
			(end -0.508 -0.9398)
			(stroke
				(width 0.1524)
				(type default)
			)
			(layer "F.SilkS")
		)
		(fp_line
			(start -0.508 -0.9398)
			(end -0.508 0.9398)
			(stroke
				(width 0.1524)
				(type default)
			)
			(layer "F.SilkS")
		)
		(fp_rect
			(start -0.508 0.9398)
			(end 0.508 -0.9398)
			(stroke
				(width 0)
				(type default)
			)
			(fill no)
			(layer "F.CrtYd")
		)
		(fp_rect
			(start -0.508 0.9398)
			(end 0.508 -0.9398)
			(stroke
				(width 0)
				(type default)
			)
			(fill no)
			(layer "F.Fab")
		)
		(pad "1" smd custom
			(at 0 -0.4445 180)
			(size 0.1397 0.1397)
			(layers "F.Cu" "F.Mask" "F.Paste")
			(net "SSD_PWREN13")
			(options
				(clearance outline)
				(anchor circle)
			)
			(primitives
				(gr_poly
					(pts
						(arc
							(start -0.1778 -0.2794)
							(mid -0.249642 -0.249642)
							(end -0.2794 -0.1778)
						)
						(arc
							(start -0.2794 0.1778)
							(mid -0.249642 0.249642)
							(end -0.1778 0.2794)
						)
						(arc
							(start 0.1778 0.2794)
							(mid 0.249642 0.249642)
							(end 0.2794 0.1778)
						)
						(arc
							(start 0.2794 -0.1778)
							(mid 0.249642 -0.249642)
							(end 0.1778 -0.2794)
						)
					)
					(width 0)
					(fill yes)
				)
			)
		)
		(pad "2" smd custom
			(at 0 0.4445 180)
			(size 0.1397 0.1397)
			(layers "F.Cu" "F.Mask" "F.Paste")
			(net "SSD_PWREN13_R")
			(options
				(clearance outline)
				(anchor circle)
			)
			(primitives
				(gr_poly
					(pts
						(arc
							(start -0.1778 -0.2794)
							(mid -0.249642 -0.249642)
							(end -0.2794 -0.1778)
						)
						(arc
							(start -0.2794 0.1778)
							(mid -0.249642 0.249642)
							(end -0.1778 0.2794)
						)
						(arc
							(start 0.1778 0.2794)
							(mid 0.249642 0.249642)
							(end 0.2794 0.1778)
						)
						(arc
							(start 0.2794 -0.1778)
							(mid 0.249642 -0.249642)
							(end 0.1778 -0.2794)
						)
					)
					(width 0)
					(fill yes)
				)
			)
		)
	)
)
